(kicad_pcb
	(version 20260206)
	(generator "pcbnew")
	(generator_version "10.0")
	(general
		(thickness 1.6)
		(legacy_teardrops no)
	)
	(paper "A4")
	(title_block
		(title "12092022_DA0F0TMDCD0_F0T_Management_Board_D_brd_V3_OCP.brd")
		(comment 1 "Grand Teton / footprints 1404-1409 of 1440")
	)
	(layers
		(0 "F.Cu" signal "TOP")
		(4 "In1.Cu" signal "GND")
		(6 "In2.Cu" signal "IN1")
		(8 "In3.Cu" signal "GND1")
		(10 "In4.Cu" signal "IN2")
		(12 "In5.Cu" signal "VCC")
		(14 "In6.Cu" signal "VCC1")
		(16 "In7.Cu" signal "IN3")
		(18 "In8.Cu" signal "GND2")
		(20 "In9.Cu" signal "IN4")
		(22 "In10.Cu" signal "GND3")
		(2 "B.Cu" signal "BOTTOM")
		(9 "F.Adhes" user "F.Adhesive")
		(11 "B.Adhes" user "B.Adhesive")
		(13 "F.Paste" user "Package Geometry/Pastemask Top")
		(15 "B.Paste" user "Package Geometry/Pastemask Bottom")
		(5 "F.SilkS" user "Ref Des/Silkscreen Top")
		(7 "B.SilkS" user "Ref Des/Silkscreen Bottom")
		(1 "F.Mask" user "Board Geometry/Soldermask Top")
		(3 "B.Mask" user "Board Geometry/Soldermask Bottom")
		(17 "Dwgs.User" user "User.Drawings")
		(19 "Cmts.User" user "User.Comments")
		(21 "Eco1.User" user "User.Eco1")
		(23 "Eco2.User" user "User.Eco2")
		(25 "Edge.Cuts" user "Board Geometry/Outline")
		(27 "Margin" user)
		(31 "F.CrtYd" user "Package Geometry/Place Bound Top")
		(29 "B.CrtYd" user "Package Geometry/Place Bound Bottom")
		(35 "F.Fab" user "Ref Des/Assembly Top")
		(33 "B.Fab" user "Ref Des/Assembly Bottom")
	)
	(footprint ""
		(layer "B.Cu")
		(at 52.555648 -37.005006 90)
		(property "Reference" "R223"
			(at 0 0 90)
			(layer "B.SilkS")
			(hide yes)
			(effects
				(font
					(size 1.27 1.27)
				)
				(justify mirror)
			)
		)
		(property "Value" ""
			(at 0 0 90)
			(layer "B.Fab")
			(effects
				(font
					(size 1.27 1.27)
				)
				(justify mirror)
			)
		)
		(duplicate_pad_numbers_are_jumpers no)
		(fp_line
			(start 0.7874 -0.4064)
			(end -0.7874 -0.4064)
			(stroke
				(width 0.1524)
				(type default)
			)
			(layer "B.SilkS")
		)
		(fp_line
			(start -0.7874 -0.4064)
			(end -0.7874 0.4064)
			(stroke
				(width 0.1524)
				(type default)
			)
			(layer "B.SilkS")
		)
		(fp_line
			(start 0.7874 0.4064)
			(end 0.7874 -0.4064)
			(stroke
				(width 0.1524)
				(type default)
			)
			(layer "B.SilkS")
		)
		(fp_line
			(start -0.7874 0.4064)
			(end 0.7874 0.4064)
			(stroke
				(width 0.1524)
				(type default)
			)
			(layer "B.SilkS")
		)
		(fp_line
			(start 0.67945 -0.305054)
			(end 0.12065 -0.305054)
			(stroke
				(width 0.1)
				(type default)
			)
			(layer "B.Fab")
		)
		(fp_line
			(start 0.12065 -0.305054)
			(end 0.12065 -0.2794)
			(stroke
				(width 0.1)
				(type default)
			)
			(layer "B.Fab")
		)
		(fp_line
			(start -0.12065 -0.3048)
			(end -0.67945 -0.3048)
			(stroke
				(width 0.1)
				(type default)
			)
			(layer "B.Fab")
		)
		(fp_line
			(start -0.67945 -0.3048)
			(end -0.67945 0.3048)
			(stroke
				(width 0.1)
				(type default)
			)
			(layer "B.Fab")
		)
		(fp_line
			(start 0.12065 -0.2794)
			(end -0.12065 -0.2794)
			(stroke
				(width 0.1)
				(type default)
			)
			(layer "B.Fab")
		)
		(fp_line
			(start -0.12065 -0.2794)
			(end -0.12065 -0.3048)
			(stroke
				(width 0.1)
				(type default)
			)
			(layer "B.Fab")
		)
		(fp_line
			(start 0.12065 0.2794)
			(end 0.12065 0.3048)
			(stroke
				(width 0.1)
				(type default)
			)
			(layer "B.Fab")
		)
		(fp_line
			(start -0.120396 0.2794)
			(end 0.12065 0.2794)
			(stroke
				(width 0.1)
				(type default)
			)
			(layer "B.Fab")
		)
		(fp_line
			(start 0.67945 0.3048)
			(end 0.67945 -0.305054)
			(stroke
				(width 0.1)
				(type default)
			)
			(layer "B.Fab")
		)
		(fp_line
			(start 0.12065 0.3048)
			(end 0.67945 0.3048)
			(stroke
				(width 0.1)
				(type default)
			)
			(layer "B.Fab")
		)
		(fp_line
			(start -0.120396 0.3048)
			(end -0.120396 0.2794)
			(stroke
				(width 0.1)
				(type default)
			)
			(layer "B.Fab")
		)
		(fp_line
			(start -0.67945 0.3048)
			(end -0.120396 0.3048)
			(stroke
				(width 0.1)
				(type default)
			)
			(layer "B.Fab")
		)
		(pad "1" smd circle
			(at 0.40005 0 270)
			(size 0 0)
			(layers "B.Cu" "B.Mask" "B.Paste")
			(net "JTAG_1_BMC_TMS_R")
		)
		(pad "2" smd circle
			(at -0.40005 0 270)
			(size 0 0)
			(layers "B.Cu" "B.Mask" "B.Paste")
			(net "JTAG_MB_TMS")
		)
	)
	(footprint ""
		(layer "B.Cu")
		(at 61.18352 -96.06788 180)
		(property "Reference" "R626"
			(at 0 0 0)
			(layer "B.SilkS")
			(hide yes)
			(effects
				(font
					(size 1.27 1.27)
				)
				(justify mirror)
			)
		)
		(property "Value" ""
			(at 0 0 0)
			(layer "B.Fab")
			(effects
				(font
					(size 1.27 1.27)
				)
				(justify mirror)
			)
		)
		(duplicate_pad_numbers_are_jumpers no)
		(fp_line
			(start 0.7874 0.4064)
			(end 0.7874 -0.4064)
			(stroke
				(width 0.1524)
				(type default)
			)
			(layer "B.SilkS")
		)
		(fp_line
			(start 0.7874 -0.4064)
			(end -0.7874 -0.4064)
			(stroke
				(width 0.1524)
				(type default)
			)
			(layer "B.SilkS")
		)
		(fp_line
			(start -0.7874 0.4064)
			(end 0.7874 0.4064)
			(stroke
				(width 0.1524)
				(type default)
			)
			(layer "B.SilkS")
		)
		(fp_line
			(start -0.7874 -0.4064)
			(end -0.7874 0.4064)
			(stroke
				(width 0.1524)
				(type default)
			)
			(layer "B.SilkS")
		)
		(fp_line
			(start 0.67945 0.3048)
			(end 0.67945 -0.305054)
			(stroke
				(width 0.1)
				(type default)
			)
			(layer "B.Fab")
		)
		(fp_line
			(start 0.67945 -0.305054)
			(end 0.12065 -0.305054)
			(stroke
				(width 0.1)
				(type default)
			)
			(layer "B.Fab")
		)
		(fp_line
			(start 0.12065 0.3048)
			(end 0.67945 0.3048)
			(stroke
				(width 0.1)
				(type default)
			)
			(layer "B.Fab")
		)
		(fp_line
			(start 0.12065 0.2794)
			(end 0.12065 0.3048)
			(stroke
				(width 0.1)
				(type default)
			)
			(layer "B.Fab")
		)
		(fp_line
			(start 0.12065 -0.2794)
			(end -0.12065 -0.2794)
			(stroke
				(width 0.1)
				(type default)
			)
			(layer "B.Fab")
		)
		(fp_line
			(start 0.12065 -0.305054)
			(end 0.12065 -0.2794)
			(stroke
				(width 0.1)
				(type default)
			)
			(layer "B.Fab")
		)
		(fp_line
			(start -0.120396 0.3048)
			(end -0.120396 0.2794)
			(stroke
				(width 0.1)
				(type default)
			)
			(layer "B.Fab")
		)
		(fp_line
			(start -0.120396 0.2794)
			(end 0.12065 0.2794)
			(stroke
				(width 0.1)
				(type default)
			)
			(layer "B.Fab")
		)
		(fp_line
			(start -0.12065 -0.2794)
			(end -0.12065 -0.3048)
			(stroke
				(width 0.1)
				(type default)
			)
			(layer "B.Fab")
		)
		(fp_line
			(start -0.12065 -0.3048)
			(end -0.67945 -0.3048)
			(stroke
				(width 0.1)
				(type default)
			)
			(layer "B.Fab")
		)
		(fp_line
			(start -0.67945 0.3048)
			(end -0.120396 0.3048)
			(stroke
				(width 0.1)
				(type default)
			)
			(layer "B.Fab")
		)
		(fp_line
			(start -0.67945 -0.3048)
			(end -0.67945 0.3048)
			(stroke
				(width 0.1)
				(type default)
			)
			(layer "B.Fab")
		)
		(pad "1" smd circle
			(at 0.40005 0)
			(size 0 0)
			(layers "B.Cu" "B.Mask" "B.Paste")
			(net "FM_SOL_UART_CH_SEL")
		)
		(pad "2" smd circle
			(at -0.40005 0)
			(size 0 0)
			(layers "B.Cu" "B.Mask" "B.Paste")
			(net "FM_SOL_UART_CH_SEL_R3")
		)
	)
	(footprint ""
		(layer "B.Cu")
		(at 65.336674 -100.265738)
		(property "Reference" "Q4"
			(at -1.963674 -1.434592 0)
			(unlocked yes)
			(layer "B.SilkS")
			(effects
				(font
					(size 0.7874 0.5842)
					(thickness 0.1524)
				)
				(justify left mirror)
			)
		)
		(property "Value" ""
			(at 0 0 0)
			(layer "B.Fab")
			(effects
				(font
					(size 1.27 1.27)
				)
				(justify mirror)
			)
		)
		(duplicate_pad_numbers_are_jumpers no)
		(fp_line
			(start -1.584198 -1.519936)
			(end -1.584198 1.519936)
			(stroke
				(width 0.1524)
				(type default)
			)
			(layer "B.SilkS")
		)
		(fp_line
			(start -1.584198 1.519936)
			(end 1.584198 1.519936)
			(stroke
				(width 0.1524)
				(type default)
			)
			(layer "B.SilkS")
		)
		(fp_line
			(start 1.584198 -1.519936)
			(end -1.584198 -1.519936)
			(stroke
				(width 0.1524)
				(type default)
			)
			(layer "B.SilkS")
		)
		(fp_line
			(start 1.584198 1.519936)
			(end 1.584198 -1.519936)
			(stroke
				(width 0.1524)
				(type default)
			)
			(layer "B.SilkS")
		)
		(fp_line
			(start -0.700024 -1.519936)
			(end -0.700024 1.519936)
			(stroke
				(width 0.1)
				(type default)
			)
			(layer "B.Fab")
		)
		(fp_line
			(start -0.700024 1.519936)
			(end 0.700024 1.519936)
			(stroke
				(width 0.1)
				(type default)
			)
			(layer "B.Fab")
		)
		(fp_line
			(start 0.700024 -1.519936)
			(end -0.700024 -1.519936)
			(stroke
				(width 0.1)
				(type default)
			)
			(layer "B.Fab")
		)
		(fp_line
			(start 0.700024 1.519936)
			(end 0.700024 -1.519936)
			(stroke
				(width 0.1)
				(type default)
			)
			(layer "B.Fab")
		)
		(pad "D" smd rect
			(at -0.999998 0 270)
			(size 0.8128 0.9144)
			(layers "B.Cu" "B.Mask" "B.Paste")
			(net "PGPPA_BMC_AUX_L")
		)
		(pad "G" smd rect
			(at 0.999998 -0.94996 270)
			(size 0.8128 0.9144)
			(layers "B.Cu" "B.Mask" "B.Paste")
			(net "LPC_ESPI_SEL_N")
		)
		(pad "S" smd rect
			(at 0.999998 0.94996 270)
			(size 0.8128 0.9144)
			(layers "B.Cu" "B.Mask" "B.Paste")
			(net "P3V3_AUX")
		)
	)
	(footprint ""
		(layer "B.Cu")
		(at 18.8722 -70.1294 -90)
		(property "Reference" "C159"
			(at 0 0 90)
			(layer "B.SilkS")
			(hide yes)
			(effects
				(font
					(size 1.27 1.27)
				)
				(justify mirror)
			)
		)
		(property "Value" ""
			(at 0 0 90)
			(layer "B.Fab")
			(effects
				(font
					(size 1.27 1.27)
				)
				(justify mirror)
			)
		)
		(duplicate_pad_numbers_are_jumpers no)
		(fp_line
			(start -0.7874 0.4064)
			(end 0.7874 0.4064)
			(stroke
				(width 0.1524)
				(type default)
			)
			(layer "B.SilkS")
		)
		(fp_line
			(start 0.7874 0.4064)
			(end 0.7874 -0.4064)
			(stroke
				(width 0.1524)
				(type default)
			)
			(layer "B.SilkS")
		)
		(fp_line
			(start -0.7874 -0.4064)
			(end -0.7874 0.4064)
			(stroke
				(width 0.1524)
				(type default)
			)
			(layer "B.SilkS")
		)
		(fp_line
			(start 0.7874 -0.4064)
			(end -0.7874 -0.4064)
			(stroke
				(width 0.1524)
				(type default)
			)
			(layer "B.SilkS")
		)
		(fp_line
			(start -0.67945 0.3048)
			(end -0.120396 0.3048)
			(stroke
				(width 0.1)
				(type default)
			)
			(layer "B.Fab")
		)
		(fp_line
			(start -0.120396 0.3048)
			(end -0.120396 0.2794)
			(stroke
				(width 0.1)
				(type default)
			)
			(layer "B.Fab")
		)
		(fp_line
			(start 0.12065 0.3048)
			(end 0.67945 0.3048)
			(stroke
				(width 0.1)
				(type default)
			)
			(layer "B.Fab")
		)
		(fp_line
			(start 0.67945 0.3048)
			(end 0.67945 -0.305054)
			(stroke
				(width 0.1)
				(type default)
			)
			(layer "B.Fab")
		)
		(fp_line
			(start -0.120396 0.2794)
			(end 0.12065 0.2794)
			(stroke
				(width 0.1)
				(type default)
			)
			(layer "B.Fab")
		)
		(fp_line
			(start 0.12065 0.2794)
			(end 0.12065 0.3048)
			(stroke
				(width 0.1)
				(type default)
			)
			(layer "B.Fab")
		)
		(fp_line
			(start -0.12065 -0.2794)
			(end -0.12065 -0.3048)
			(stroke
				(width 0.1)
				(type default)
			)
			(layer "B.Fab")
		)
		(fp_line
			(start 0.12065 -0.2794)
			(end -0.12065 -0.2794)
			(stroke
				(width 0.1)
				(type default)
			)
			(layer "B.Fab")
		)
		(fp_line
			(start -0.67945 -0.3048)
			(end -0.67945 0.3048)
			(stroke
				(width 0.1)
				(type default)
			)
			(layer "B.Fab")
		)
		(fp_line
			(start -0.12065 -0.3048)
			(end -0.67945 -0.3048)
			(stroke
				(width 0.1)
				(type default)
			)
			(layer "B.Fab")
		)
		(fp_line
			(start 0.12065 -0.305054)
			(end 0.12065 -0.2794)
			(stroke
				(width 0.1)
				(type default)
			)
			(layer "B.Fab")
		)
		(fp_line
			(start 0.67945 -0.305054)
			(end 0.12065 -0.305054)
			(stroke
				(width 0.1)
				(type default)
			)
			(layer "B.Fab")
		)
		(pad "1" smd circle
			(at 0.40005 0 90)
			(size 0 0)
			(layers "B.Cu" "B.Mask" "B.Paste")
			(net "P3V3_AUX")
		)
		(pad "2" smd circle
			(at -0.40005 0 90)
			(size 0 0)
			(layers "B.Cu" "B.Mask" "B.Paste")
			(net "GND")
		)
	)
	(footprint ""
		(layer "B.Cu")
		(at 21.971 -17.907 90)
		(property "Reference" "R569"
			(at 0 0 90)
			(layer "B.SilkS")
			(hide yes)
			(effects
				(font
					(size 1.27 1.27)
				)
				(justify mirror)
			)
		)
		(property "Value" ""
			(at 0 0 90)
			(layer "B.Fab")
			(effects
				(font
					(size 1.27 1.27)
				)
				(justify mirror)
			)
		)
		(duplicate_pad_numbers_are_jumpers no)
		(fp_line
			(start 0.7874 -0.4064)
			(end -0.7874 -0.4064)
			(stroke
				(width 0.1524)
				(type default)
			)
			(layer "B.SilkS")
		)
		(fp_line
			(start -0.7874 -0.4064)
			(end -0.7874 0.4064)
			(stroke
				(width 0.1524)
				(type default)
			)
			(layer "B.SilkS")
		)
		(fp_line
			(start 0.7874 0.4064)
			(end 0.7874 -0.4064)
			(stroke
				(width 0.1524)
				(type default)
			)
			(layer "B.SilkS")
		)
		(fp_line
			(start -0.7874 0.4064)
			(end 0.7874 0.4064)
			(stroke
				(width 0.1524)
				(type default)
			)
			(layer "B.SilkS")
		)
		(fp_line
			(start 0.67945 -0.305054)
			(end 0.12065 -0.305054)
			(stroke
				(width 0.1)
				(type default)
			)
			(layer "B.Fab")
		)
		(fp_line
			(start 0.12065 -0.305054)
			(end 0.12065 -0.2794)
			(stroke
				(width 0.1)
				(type default)
			)
			(layer "B.Fab")
		)
		(fp_line
			(start -0.12065 -0.3048)
			(end -0.67945 -0.3048)
			(stroke
				(width 0.1)
				(type default)
			)
			(layer "B.Fab")
		)
		(fp_line
			(start -0.67945 -0.3048)
			(end -0.67945 0.3048)
			(stroke
				(width 0.1)
				(type default)
			)
			(layer "B.Fab")
		)
		(fp_line
			(start 0.12065 -0.2794)
			(end -0.12065 -0.2794)
			(stroke
				(width 0.1)
				(type default)
			)
			(layer "B.Fab")
		)
		(fp_line
			(start -0.12065 -0.2794)
			(end -0.12065 -0.3048)
			(stroke
				(width 0.1)
				(type default)
			)
			(layer "B.Fab")
		)
		(fp_line
			(start 0.12065 0.2794)
			(end 0.12065 0.3048)
			(stroke
				(width 0.1)
				(type default)
			)
			(layer "B.Fab")
		)
		(fp_line
			(start -0.120396 0.2794)
			(end 0.12065 0.2794)
			(stroke
				(width 0.1)
				(type default)
			)
			(layer "B.Fab")
		)
		(fp_line
			(start 0.67945 0.3048)
			(end 0.67945 -0.305054)
			(stroke
				(width 0.1)
				(type default)
			)
			(layer "B.Fab")
		)
		(fp_line
			(start 0.12065 0.3048)
			(end 0.67945 0.3048)
			(stroke
				(width 0.1)
				(type default)
			)
			(layer "B.Fab")
		)
		(fp_line
			(start -0.120396 0.3048)
			(end -0.120396 0.2794)
			(stroke
				(width 0.1)
				(type default)
			)
			(layer "B.Fab")
		)
		(fp_line
			(start -0.67945 0.3048)
			(end -0.120396 0.3048)
			(stroke
				(width 0.1)
				(type default)
			)
			(layer "B.Fab")
		)
		(pad "1" smd circle
			(at 0.40005 0 270)
			(size 0 0)
			(layers "B.Cu" "B.Mask" "B.Paste")
			(net "HDD_LED_P5V_AUX")
		)
		(pad "2" smd circle
			(at -0.40005 0 270)
			(size 0 0)
			(layers "B.Cu" "B.Mask" "B.Paste")
			(net "P5V_AUX")
		)
	)
	(footprint ""
		(layer "B.Cu")
		(at 19.939 -101.981 -90)
		(property "Reference" "R321"
			(at 0 0 90)
			(layer "B.SilkS")
			(hide yes)
			(effects
				(font
					(size 1.27 1.27)
				)
				(justify mirror)
			)
		)
		(property "Value" ""
			(at 0 0 90)
			(layer "B.Fab")
			(effects
				(font
					(size 1.27 1.27)
				)
				(justify mirror)
			)
		)
		(duplicate_pad_numbers_are_jumpers no)
		(fp_line
			(start -0.7874 0.4064)
			(end 0.7874 0.4064)
			(stroke
				(width 0.1524)
				(type default)
			)
			(layer "B.SilkS")
		)
		(fp_line
			(start 0.7874 0.4064)
			(end 0.7874 -0.4064)
			(stroke
				(width 0.1524)
				(type default)
			)
			(layer "B.SilkS")
		)
		(fp_line
			(start -0.7874 -0.4064)
			(end -0.7874 0.4064)
			(stroke
				(width 0.1524)
				(type default)
			)
			(layer "B.SilkS")
		)
		(fp_line
			(start 0.7874 -0.4064)
			(end -0.7874 -0.4064)
			(stroke
				(width 0.1524)
				(type default)
			)
			(layer "B.SilkS")
		)
		(fp_line
			(start -0.67945 0.3048)
			(end -0.120396 0.3048)
			(stroke
				(width 0.1)
				(type default)
			)
			(layer "B.Fab")
		)
		(fp_line
			(start -0.120396 0.3048)
			(end -0.120396 0.2794)
			(stroke
				(width 0.1)
				(type default)
			)
			(layer "B.Fab")
		)
		(fp_line
			(start 0.12065 0.3048)
			(end 0.67945 0.3048)
			(stroke
				(width 0.1)
				(type default)
			)
			(layer "B.Fab")
		)
		(fp_line
			(start 0.67945 0.3048)
			(end 0.67945 -0.305054)
			(stroke
				(width 0.1)
				(type default)
			)
			(layer "B.Fab")
		)
		(fp_line
			(start -0.120396 0.2794)
			(end 0.12065 0.2794)
			(stroke
				(width 0.1)
				(type default)
			)
			(layer "B.Fab")
		)
		(fp_line
			(start 0.12065 0.2794)
			(end 0.12065 0.3048)
			(stroke
				(width 0.1)
				(type default)
			)
			(layer "B.Fab")
		)
		(fp_line
			(start -0.12065 -0.2794)
			(end -0.12065 -0.3048)
			(stroke
				(width 0.1)
				(type default)
			)
			(layer "B.Fab")
		)
		(fp_line
			(start 0.12065 -0.2794)
			(end -0.12065 -0.2794)
			(stroke
				(width 0.1)
				(type default)
			)
			(layer "B.Fab")
		)
		(fp_line
			(start -0.67945 -0.3048)
			(end -0.67945 0.3048)
			(stroke
				(width 0.1)
				(type default)
			)
			(layer "B.Fab")
		)
		(fp_line
			(start -0.12065 -0.3048)
			(end -0.67945 -0.3048)
			(stroke
				(width 0.1)
				(type default)
			)
			(layer "B.Fab")
		)
		(fp_line
			(start 0.12065 -0.305054)
			(end 0.12065 -0.2794)
			(stroke
				(width 0.1)
				(type default)
			)
			(layer "B.Fab")
		)
		(fp_line
			(start 0.67945 -0.305054)
			(end 0.12065 -0.305054)
			(stroke
				(width 0.1)
				(type default)
			)
			(layer "B.Fab")
		)
		(pad "1" smd circle
			(at 0.40005 0 90)
			(size 0 0)
			(layers "B.Cu" "B.Mask" "B.Paste")
			(net "PWRGD_P1V8_AUX_R1")
		)
		(pad "2" smd circle
			(at -0.40005 0 90)
			(size 0 0)
			(layers "B.Cu" "B.Mask" "B.Paste")
			(net "PWRGD_P1V8_AUX")
		)
	)
)
